# BASEBOARD_FAB2 (Tioga Pass) — schematic netlist excerpt (pin names and nets, part order shuffled) for the footprints in the layout excerpt that follows; sources: Cadence DE-HDL packaged netlist, KiCad conversion of Wiwynn_Tioga_Pass_MB.brd

C7G14  CAP  0.22UF 16V 10% X7R  pkg 0402  page 105 : A = P3E_CPU0_PE2_SS_TXP<11> ; B = P3E_CPU0_PE2_SS_C_TXP<11>
R12W35  RES  0.0 5% EMPTY  pkg 0402  page 226 : A = NC_PVDDQ_KLM_GP1 ; B = PWRGD_PVDDQ_KLM
C30W3  SC22U16V5MX-4-GP  20%  pkg SMD-BCG5  page 253 : \1\ = P5V_STBY_USBC ; \2\ = GND

(kicad_pcb
	(version 20260206)
	(generator "pcbnew")
	(generator_version "10.0")
	(general
		(thickness 1.6)
		(legacy_teardrops no)
	)
	(paper "A4")
	(title_block
		(title "Wiwynn_Tioga_Pass_MB.brd")
		(comment 1 "Tioga Pass / footprints 130-132 of 4770")
	)
	(layers
		(0 "F.Cu" signal "TOP")
		(4 "In1.Cu" signal "L2GND")
		(6 "In2.Cu" signal "L3")
		(8 "In3.Cu" signal "L4GND")
		(10 "In4.Cu" signal "L5")
		(12 "In5.Cu" signal "L6GND")
		(14 "In6.Cu" signal "L7VCC")
		(16 "In7.Cu" signal "L8VCC")
		(18 "In8.Cu" signal "L9GND")
		(20 "In9.Cu" signal "L10")
		(22 "In10.Cu" signal "L11GND")
		(24 "In11.Cu" signal "L12")
		(26 "In12.Cu" signal "L13GND")
		(2 "B.Cu" signal "BOTTOM")
		(9 "F.Adhes" user "F.Adhesive")
		(11 "B.Adhes" user "B.Adhesive")
		(13 "F.Paste" user "Package Geometry/Pastemask Top")
		(15 "B.Paste" user "Package Geometry/Pastemask Bottom")
		(5 "F.SilkS" user "Ref Des/Silkscreen Top")
		(7 "B.SilkS" user "Ref Des/Silkscreen Bottom")
		(1 "F.Mask" user "Board Geometry/Soldermask Top")
		(3 "B.Mask" user "Board Geometry/Soldermask Bottom")
		(17 "Dwgs.User" user "User.Drawings")
		(19 "Cmts.User" user "User.Comments")
		(21 "Eco1.User" user "User.Eco1")
		(23 "Eco2.User" user "User.Eco2")
		(25 "Edge.Cuts" user "Board Geometry/Outline")
		(27 "Margin" user)
		(31 "F.CrtYd" user "Package Geometry/Place Bound Top")
		(29 "B.CrtYd" user "Package Geometry/Place Bound Bottom")
		(35 "F.Fab" user "Ref Des/Assembly Top")
		(33 "B.Fab" user "Ref Des/Assembly Bottom")
	)
	(footprint ""
		(layer "F.Cu")
		(at 372.766844 -10.916158)
		(property "Reference" "C7G14"
			(at 0 0 0)
			(layer "F.SilkS")
			(hide yes)
			(effects
				(font
					(size 1.27 1.27)
				)
			)
		)
		(property "Value" ""
			(at 0 0 0)
			(layer "F.Fab")
			(effects
				(font
					(size 1.27 1.27)
				)
			)
		)
		(duplicate_pad_numbers_are_jumpers no)
		(fp_rect
			(start -0.3048 0.9906)
			(end 0.3048 -0.1016)
			(stroke
				(width 0)
				(type default)
			)
			(fill no)
			(layer "F.CrtYd")
		)
		(fp_line
			(start -0.3048 -0.1016)
			(end -0.3048 0.9906)
			(stroke
				(width 0.1)
				(type default)
			)
			(layer "F.Fab")
		)
		(fp_line
			(start -0.3048 0.9906)
			(end 0.3048 0.9906)
			(stroke
				(width 0.1)
				(type default)
			)
			(layer "F.Fab")
		)
		(fp_line
			(start 0.3048 -0.1016)
			(end -0.3048 -0.1016)
			(stroke
				(width 0.1)
				(type default)
			)
			(layer "F.Fab")
		)
		(fp_line
			(start 0.3048 0.9906)
			(end 0.3048 -0.1016)
			(stroke
				(width 0.1)
				(type default)
			)
			(layer "F.Fab")
		)
		(pad "1" smd rect
			(at 0 0)
			(size 0.508 0.508)
			(layers "F.Cu" "F.Mask" "F.Paste")
			(net "P3E_CPU0_PE2_SS_TXP<11>")
		)
		(pad "2" smd rect
			(at 0 0.889)
			(size 0.508 0.508)
			(layers "F.Cu" "F.Mask" "F.Paste")
			(net "P3E_CPU0_PE2_SS_C_TXP<11>")
		)
		(zone
			(layer "F.Cu")
			(hatch none 0.5)
			(connect_pads
				(clearance 0)
			)
			(min_thickness 0.25)
			(keepout
				(tracks allowed)
				(vias not_allowed)
				(pads allowed)
				(copperpour not_allowed)
				(footprints allowed)
			)
			(placement
				(enabled no)
				(sheetname "")
			)
			(fill
				(thermal_gap 0.5)
				(thermal_bridge_width 0.5)
				(island_removal_mode 0)
			)
			(polygon
				(pts
					(xy 372.512844 -10.281158) (xy 373.020844 -10.281158) (xy 373.020844 -10.662158) (xy 372.512844 -10.662158)
				)
			)
		)
		(zone
			(layer "F.Cu")
			(hatch none 0.5)
			(connect_pads
				(clearance 0)
			)
			(min_thickness 0.25)
			(keepout
				(tracks not_allowed)
				(vias allowed)
				(pads allowed)
				(copperpour not_allowed)
				(footprints allowed)
			)
			(placement
				(enabled no)
				(sheetname "")
			)
			(fill
				(thermal_gap 0.5)
				(thermal_bridge_width 0.5)
				(island_removal_mode 0)
			)
			(polygon
				(pts
					(xy 372.512844 -10.281158) (xy 373.020844 -10.281158) (xy 373.020844 -10.662158) (xy 372.512844 -10.662158)
				)
			)
		)
	)
	(footprint ""
		(layer "F.Cu")
		(at 492.4806 -59.944 180)
		(property "Reference" "C30W3"
			(at 0 0 180)
			(layer "F.SilkS")
			(hide yes)
			(effects
				(font
					(size 1.27 1.27)
				)
			)
		)
		(property "Value" "*"
			(at -0.0762 -6.2357 180)
			(unlocked yes)
			(layer "F.Fab")
			(hide yes)
			(effects
				(font
					(size 1.27 1.016)
					(thickness 0.1524)
				)
			)
		)
		(property "Device Type" "SC22U16V5MX-4-GP_SMD-BCG5-SC22A"
			(at -0.0762 -8.2677 180)
			(unlocked yes)
			(layer "F.Fab")
			(hide yes)
			(effects
				(font
					(size 1.27 1.016)
					(thickness 0.1524)
				)
			)
		)
		(duplicate_pad_numbers_are_jumpers no)
		(fp_line
			(start 0.635 0)
			(end -0.635 0)
			(stroke
				(width 0.508)
				(type default)
			)
			(layer "F.SilkS")
		)
		(fp_rect
			(start -0.9652 1.778)
			(end 0.9652 -1.778)
			(stroke
				(width 0)
				(type default)
			)
			(fill no)
			(layer "F.CrtYd")
		)
		(fp_poly
			(pts
				(xy -0.9652 -1.778) (xy 0.9652 -1.778) (xy 0.9652 1.778) (xy -0.9652 1.778)
			)
			(stroke
				(width 0)
				(type default)
			)
			(fill no)
			(layer "F.Fab")
		)
		(pad "1" smd rect
			(at 0 -0.9652 180)
			(size 1.397 1.143)
			(layers "F.Cu" "F.Mask" "F.Paste")
			(net "P5V_STBY_USBC")
		)
		(pad "2" smd rect
			(at 0 0.9652 180)
			(size 1.397 1.143)
			(layers "F.Cu" "F.Mask" "F.Paste")
			(net "GND")
		)
	)
	(footprint ""
		(layer "F.Cu")
		(at -2.667 -129.3622 -90)
		(property "Reference" "R12W35"
			(at -0.8382 -0.67818 270)
			(unlocked yes)
			(layer "F.SilkS")
			(effects
				(font
					(size 0.4064 0.254)
					(thickness 0.1524)
				)
				(justify left)
			)
		)
		(property "Value" ""
			(at 0 0 270)
			(layer "F.Fab")
			(effects
				(font
					(size 1.27 1.27)
				)
			)
		)
		(duplicate_pad_numbers_are_jumpers no)
		(fp_poly
			(pts
				(xy -0.2794 -0.1016) (xy 0.2794 -0.1016) (xy 0.2794 0.9906) (xy -0.2794 0.9906)
			)
			(stroke
				(width 0)
				(type default)
			)
			(fill no)
			(layer "F.CrtYd")
		)
		(fp_line
			(start -0.2794 0.9906)
			(end 0.2794 0.9906)
			(stroke
				(width 0.1)
				(type default)
			)
			(layer "F.Fab")
		)
		(fp_line
			(start 0.2794 0.9906)
			(end 0.2794 -0.1016)
			(stroke
				(width 0.1)
				(type default)
			)
			(layer "F.Fab")
		)
		(fp_line
			(start -0.2794 -0.1016)
			(end -0.2794 0.9906)
			(stroke
				(width 0.1)
				(type default)
			)
			(layer "F.Fab")
		)
		(fp_line
			(start 0.2794 -0.1016)
			(end -0.2794 -0.1016)
			(stroke
				(width 0.1)
				(type default)
			)
			(layer "F.Fab")
		)
		(pad "1" smd rect
			(at 0 0 270)
			(size 0.508 0.508)
			(layers "F.Cu" "F.Mask" "F.Paste")
			(net "NC_PVDDQ_KLM_GP1")
		)
		(pad "2" smd rect
			(at 0 0.889 270)
			(size 0.508 0.508)
			(layers "F.Cu" "F.Mask" "F.Paste")
			(net "PWRGD_PVDDQ_KLM")
		)
		(zone
			(layer "F.Cu")
			(hatch none 0.5)
			(connect_pads
				(clearance 0)
			)
			(min_thickness 0.25)
			(keepout
				(tracks not_allowed)
				(vias allowed)
				(pads allowed)
				(copperpour not_allowed)
				(footprints allowed)
			)
			(placement
				(enabled no)
				(sheetname "")
			)
			(fill
				(thermal_gap 0.5)
				(thermal_bridge_width 0.5)
				(island_removal_mode 0)
			)
			(polygon
				(pts
					(xy -3.302 -129.6162) (xy -3.302 -129.1082) (xy -2.921 -129.1082) (xy -2.921 -129.6162)
				)
			)
		)
		(zone
			(layer "F.Cu")
			(hatch none 0.5)
			(connect_pads
				(clearance 0)
			)
			(min_thickness 0.25)
			(keepout
				(tracks allowed)
				(vias not_allowed)
				(pads allowed)
				(copperpour not_allowed)
				(footprints allowed)
			)
			(placement
				(enabled no)
				(sheetname "")
			)
			(fill
				(thermal_gap 0.5)
				(thermal_bridge_width 0.5)
				(island_removal_mode 0)
			)
			(polygon
				(pts
					(xy -2.921 -129.6162) (xy -2.921 -129.1082) (xy -3.302 -129.1082) (xy -3.302 -129.6162)
				)
			)
		)
	)
)
